(kicad_pcb
	(version 20260206)
	(generator "pcbnew")
	(generator_version "10.0")
	(general
		(thickness 1.6)
		(legacy_teardrops no)
	)
	(paper "A4")
	(title_block
		(title "Wiwynn_Tioga_Pass_MB.brd")
		(comment 1 "Tioga Pass / footprints 853-857 of 4770")
	)
	(layers
		(0 "F.Cu" signal "TOP")
		(4 "In1.Cu" signal "L2GND")
		(6 "In2.Cu" signal "L3")
		(8 "In3.Cu" signal "L4GND")
		(10 "In4.Cu" signal "L5")
		(12 "In5.Cu" signal "L6GND")
		(14 "In6.Cu" signal "L7VCC")
		(16 "In7.Cu" signal "L8VCC")
		(18 "In8.Cu" signal "L9GND")
		(20 "In9.Cu" signal "L10")
		(22 "In10.Cu" signal "L11GND")
		(24 "In11.Cu" signal "L12")
		(26 "In12.Cu" signal "L13GND")
		(2 "B.Cu" signal "BOTTOM")
		(9 "F.Adhes" user "F.Adhesive")
		(11 "B.Adhes" user "B.Adhesive")
		(13 "F.Paste" user "Package Geometry/Pastemask Top")
		(15 "B.Paste" user "Package Geometry/Pastemask Bottom")
		(5 "F.SilkS" user "Ref Des/Silkscreen Top")
		(7 "B.SilkS" user "Ref Des/Silkscreen Bottom")
		(1 "F.Mask" user "Board Geometry/Soldermask Top")
		(3 "B.Mask" user "Board Geometry/Soldermask Bottom")
		(17 "Dwgs.User" user "User.Drawings")
		(19 "Cmts.User" user "User.Comments")
		(21 "Eco1.User" user "User.Eco1")
		(23 "Eco2.User" user "User.Eco2")
		(25 "Edge.Cuts" user "Board Geometry/Outline")
		(27 "Margin" user)
		(31 "F.CrtYd" user "Package Geometry/Place Bound Top")
		(29 "B.CrtYd" user "Package Geometry/Place Bound Bottom")
		(35 "F.Fab" user "Ref Des/Assembly Top")
		(33 "B.Fab" user "Ref Des/Assembly Bottom")
	)
	(footprint ""
		(layer "F.Cu")
		(at 398.39392 -68.59016 90)
		(property "Reference" "L8E1"
			(at -4.3434 7.72287 90)
			(unlocked yes)
			(layer "F.SilkS")
			(effects
				(font
					(size 0.7874 0.5842)
					(thickness 0.1524)
				)
				(justify left)
			)
		)
		(property "Value" ""
			(at 0 0 90)
			(layer "F.Fab")
			(effects
				(font
					(size 1.27 1.27)
				)
			)
		)
		(duplicate_pad_numbers_are_jumpers no)
		(fp_line
			(start 3.4036 -0.6731)
			(end 3.4036 6.1341)
			(stroke
				(width 0.1524)
				(type default)
			)
			(layer "F.SilkS")
		)
		(fp_line
			(start 2.5654 -0.6731)
			(end 3.4036 -0.6731)
			(stroke
				(width 0.1524)
				(type default)
			)
			(layer "F.SilkS")
		)
		(fp_line
			(start -3.4036 -0.6731)
			(end -2.5654 -0.6731)
			(stroke
				(width 0.1524)
				(type default)
			)
			(layer "F.SilkS")
		)
		(fp_line
			(start 3.4036 6.1341)
			(end 2.5654 6.1341)
			(stroke
				(width 0.1524)
				(type default)
			)
			(layer "F.SilkS")
		)
		(fp_line
			(start -2.5654 6.1341)
			(end -3.4036 6.1341)
			(stroke
				(width 0.1524)
				(type default)
			)
			(layer "F.SilkS")
		)
		(fp_line
			(start -3.4036 6.1341)
			(end -3.4036 -0.6731)
			(stroke
				(width 0.1524)
				(type default)
			)
			(layer "F.SilkS")
		)
		(fp_poly
			(pts
				(xy -3.4036 -0.6731) (xy -3.4036 6.1341) (xy 3.4036 6.1341) (xy 3.4036 -0.6731)
			)
			(stroke
				(width 0)
				(type default)
			)
			(fill no)
			(layer "F.CrtYd")
		)
		(fp_line
			(start 3.4036 -0.6731)
			(end 3.4036 6.1341)
			(stroke
				(width 0.1)
				(type default)
			)
			(layer "F.Fab")
		)
		(fp_line
			(start -3.4036 -0.6731)
			(end 3.4036 -0.6731)
			(stroke
				(width 0.1)
				(type default)
			)
			(layer "F.Fab")
		)
		(fp_line
			(start 3.4036 6.1341)
			(end -3.4036 6.1341)
			(stroke
				(width 0.1)
				(type default)
			)
			(layer "F.Fab")
		)
		(fp_line
			(start -3.4036 6.1341)
			(end -3.4036 -0.6731)
			(stroke
				(width 0.1)
				(type default)
			)
			(layer "F.Fab")
		)
		(pad "1" smd rect
			(at 0 0 90)
			(size 3.556 3.175)
			(layers "F.Cu" "F.Mask" "F.Paste")
			(net "VR_P5V_STBY_PHASE")
		)
		(pad "2" smd rect
			(at 0 5.461 90)
			(size 3.556 3.175)
			(layers "F.Cu" "F.Mask" "F.Paste")
			(net "P5V_STBY")
		)
	)
	(footprint ""
		(layer "F.Cu")
		(at 180.2257 -77.31125 90)
		(property "Reference" "R4D26"
			(at 0 0 90)
			(layer "F.SilkS")
			(hide yes)
			(effects
				(font
					(size 1.27 1.27)
				)
			)
		)
		(property "Value" ""
			(at 0 0 90)
			(layer "F.Fab")
			(effects
				(font
					(size 1.27 1.27)
				)
			)
		)
		(duplicate_pad_numbers_are_jumpers no)
		(fp_rect
			(start -0.2794 -0.1016)
			(end 0.2794 0.9906)
			(stroke
				(width 0)
				(type default)
			)
			(fill no)
			(layer "F.CrtYd")
		)
		(fp_line
			(start 0.2794 -0.1016)
			(end -0.2794 -0.1016)
			(stroke
				(width 0.1)
				(type default)
			)
			(layer "F.Fab")
		)
		(fp_line
			(start -0.2794 -0.1016)
			(end -0.2794 0.9906)
			(stroke
				(width 0.1)
				(type default)
			)
			(layer "F.Fab")
		)
		(fp_line
			(start 0.2794 0.9906)
			(end 0.2794 -0.1016)
			(stroke
				(width 0.1)
				(type default)
			)
			(layer "F.Fab")
		)
		(fp_line
			(start -0.2794 0.9906)
			(end 0.2794 0.9906)
			(stroke
				(width 0.1)
				(type default)
			)
			(layer "F.Fab")
		)
		(pad "1" smd rect
			(at 0 0 90)
			(size 0.508 0.508)
			(layers "F.Cu" "F.Mask" "F.Paste")
			(net "P3V3_STBY")
		)
		(pad "2" smd rect
			(at 0 0.889 90)
			(size 0.508 0.508)
			(layers "F.Cu" "F.Mask" "F.Paste")
			(net "VR_PVCCIN_CPU0_VDD")
		)
		(zone
			(layer "F.Cu")
			(hatch none 0.5)
			(connect_pads
				(clearance 0)
			)
			(min_thickness 0.25)
			(keepout
				(tracks not_allowed)
				(vias allowed)
				(pads allowed)
				(copperpour not_allowed)
				(footprints allowed)
			)
			(placement
				(enabled no)
				(sheetname "")
			)
			(fill
				(thermal_gap 0.5)
				(thermal_bridge_width 0.5)
				(island_removal_mode 0)
			)
			(polygon
				(pts
					(xy 180.4797 -77.05725) (xy 180.8607 -77.05725) (xy 180.8607 -77.56525) (xy 180.4797 -77.56525)
				)
			)
		)
		(zone
			(layer "F.Cu")
			(hatch none 0.5)
			(connect_pads
				(clearance 0)
			)
			(min_thickness 0.25)
			(keepout
				(tracks allowed)
				(vias not_allowed)
				(pads allowed)
				(copperpour not_allowed)
				(footprints allowed)
			)
			(placement
				(enabled no)
				(sheetname "")
			)
			(fill
				(thermal_gap 0.5)
				(thermal_bridge_width 0.5)
				(island_removal_mode 0)
			)
			(polygon
				(pts
					(xy 180.4797 -77.05725) (xy 180.8607 -77.05725) (xy 180.8607 -77.56525) (xy 180.4797 -77.56525)
				)
			)
		)
	)
	(footprint ""
		(layer "F.Cu")
		(at 181.991 -12.6365 180)
		(property "Reference" "C4G4"
			(at 0 0 180)
			(layer "F.SilkS")
			(hide yes)
			(effects
				(font
					(size 1.27 1.27)
				)
			)
		)
		(property "Value" ""
			(at 0 0 180)
			(layer "F.Fab")
			(effects
				(font
					(size 1.27 1.27)
				)
			)
		)
		(duplicate_pad_numbers_are_jumpers no)
		(fp_poly
			(pts
				(xy 0.3048 -0.1016) (xy 0.3048 0.9906) (xy -0.3048 0.9906) (xy -0.3048 -0.1016)
			)
			(stroke
				(width 0)
				(type default)
			)
			(fill no)
			(layer "F.CrtYd")
		)
		(fp_line
			(start 0.3048 0.9906)
			(end 0.3048 -0.1016)
			(stroke
				(width 0.1)
				(type default)
			)
			(layer "F.Fab")
		)
		(fp_line
			(start 0.3048 -0.1016)
			(end -0.3048 -0.1016)
			(stroke
				(width 0.1)
				(type default)
			)
			(layer "F.Fab")
		)
		(fp_line
			(start -0.3048 0.9906)
			(end 0.3048 0.9906)
			(stroke
				(width 0.1)
				(type default)
			)
			(layer "F.Fab")
		)
		(fp_line
			(start -0.3048 -0.1016)
			(end -0.3048 0.9906)
			(stroke
				(width 0.1)
				(type default)
			)
			(layer "F.Fab")
		)
		(pad "1" smd rect
			(at 0 0 180)
			(size 0.508 0.508)
			(layers "F.Cu" "F.Mask" "F.Paste")
			(net "VR_FET_SW_P12V_STBY_PVPP_GHJ")
		)
		(pad "2" smd rect
			(at 0 0.889 180)
			(size 0.508 0.508)
			(layers "F.Cu" "F.Mask" "F.Paste")
			(net "GND")
		)
		(zone
			(layer "F.Cu")
			(hatch none 0.5)
			(connect_pads
				(clearance 0)
			)
			(min_thickness 0.25)
			(keepout
				(tracks not_allowed)
				(vias allowed)
				(pads allowed)
				(copperpour not_allowed)
				(footprints allowed)
			)
			(placement
				(enabled no)
				(sheetname "")
			)
			(fill
				(thermal_gap 0.5)
				(thermal_bridge_width 0.5)
				(island_removal_mode 0)
			)
			(polygon
				(pts
					(xy 182.245 -13.2715) (xy 181.737 -13.2715) (xy 181.737 -12.8905) (xy 182.245 -12.8905)
				)
			)
		)
		(zone
			(layer "F.Cu")
			(hatch none 0.5)
			(connect_pads
				(clearance 0)
			)
			(min_thickness 0.25)
			(keepout
				(tracks allowed)
				(vias not_allowed)
				(pads allowed)
				(copperpour not_allowed)
				(footprints allowed)
			)
			(placement
				(enabled no)
				(sheetname "")
			)
			(fill
				(thermal_gap 0.5)
				(thermal_bridge_width 0.5)
				(island_removal_mode 0)
			)
			(polygon
				(pts
					(xy 182.245 -12.8905) (xy 181.737 -12.8905) (xy 181.737 -13.2715) (xy 182.245 -13.2715)
				)
			)
		)
	)
	(footprint ""
		(layer "F.Cu")
		(at 167.00627 -34.9631 90)
		(property "Reference" "C4F1"
			(at 0 0 90)
			(layer "F.SilkS")
			(hide yes)
			(effects
				(font
					(size 1.27 1.27)
				)
			)
		)
		(property "Value" ""
			(at 0 0 90)
			(layer "F.Fab")
			(effects
				(font
					(size 1.27 1.27)
				)
			)
		)
		(duplicate_pad_numbers_are_jumpers no)
		(fp_poly
			(pts
				(xy 0.3048 -0.1016) (xy 0.3048 0.9906) (xy -0.3048 0.9906) (xy -0.3048 -0.1016)
			)
			(stroke
				(width 0)
				(type default)
			)
			(fill no)
			(layer "F.CrtYd")
		)
		(fp_line
			(start 0.3048 -0.1016)
			(end -0.3048 -0.1016)
			(stroke
				(width 0.1)
				(type default)
			)
			(layer "F.Fab")
		)
		(fp_line
			(start -0.3048 -0.1016)
			(end -0.3048 0.9906)
			(stroke
				(width 0.1)
				(type default)
			)
			(layer "F.Fab")
		)
		(fp_line
			(start 0.3048 0.9906)
			(end 0.3048 -0.1016)
			(stroke
				(width 0.1)
				(type default)
			)
			(layer "F.Fab")
		)
		(fp_line
			(start -0.3048 0.9906)
			(end 0.3048 0.9906)
			(stroke
				(width 0.1)
				(type default)
			)
			(layer "F.Fab")
		)
		(pad "1" smd rect
			(at 0 0 90)
			(size 0.508 0.508)
			(layers "F.Cu" "F.Mask" "F.Paste")
			(net "P1V8_MCP_CPU1")
		)
		(pad "2" smd rect
			(at 0 0.889 90)
			(size 0.508 0.508)
			(layers "F.Cu" "F.Mask" "F.Paste")
			(net "GND")
		)
		(zone
			(layer "F.Cu")
			(hatch none 0.5)
			(connect_pads
				(clearance 0)
			)
			(min_thickness 0.25)
			(keepout
				(tracks allowed)
				(vias not_allowed)
				(pads allowed)
				(copperpour not_allowed)
				(footprints allowed)
			)
			(placement
				(enabled no)
				(sheetname "")
			)
			(fill
				(thermal_gap 0.5)
				(thermal_bridge_width 0.5)
				(island_removal_mode 0)
			)
			(polygon
				(pts
					(xy 167.26027 -34.7091) (xy 167.26027 -35.2171) (xy 167.64127 -35.2171) (xy 167.64127 -34.7091)
				)
			)
		)
		(zone
			(layer "F.Cu")
			(hatch none 0.5)
			(connect_pads
				(clearance 0)
			)
			(min_thickness 0.25)
			(keepout
				(tracks not_allowed)
				(vias allowed)
				(pads allowed)
				(copperpour not_allowed)
				(footprints allowed)
			)
			(placement
				(enabled no)
				(sheetname "")
			)
			(fill
				(thermal_gap 0.5)
				(thermal_bridge_width 0.5)
				(island_removal_mode 0)
			)
			(polygon
				(pts
					(xy 167.64127 -34.7091) (xy 167.64127 -35.2171) (xy 167.26027 -35.2171) (xy 167.26027 -34.7091)
				)
			)
		)
	)
	(footprint ""
		(layer "F.Cu")
		(at 28.438348 -80.3148 -90)
		(property "Reference" "R1D54"
			(at 0 0 270)
			(layer "F.SilkS")
			(hide yes)
			(effects
				(font
					(size 1.27 1.27)
				)
			)
		)
		(property "Value" ""
			(at 0 0 270)
			(layer "F.Fab")
			(effects
				(font
					(size 1.27 1.27)
				)
			)
		)
		(duplicate_pad_numbers_are_jumpers no)
		(fp_poly
			(pts
				(xy -0.2794 -0.1016) (xy 0.2794 -0.1016) (xy 0.2794 0.9906) (xy -0.2794 0.9906)
			)
			(stroke
				(width 0)
				(type default)
			)
			(fill no)
			(layer "F.CrtYd")
		)
		(fp_line
			(start -0.2794 0.9906)
			(end 0.2794 0.9906)
			(stroke
				(width 0.1)
				(type default)
			)
			(layer "F.Fab")
		)
		(fp_line
			(start 0.2794 0.9906)
			(end 0.2794 -0.1016)
			(stroke
				(width 0.1)
				(type default)
			)
			(layer "F.Fab")
		)
		(fp_line
			(start -0.2794 -0.1016)
			(end -0.2794 0.9906)
			(stroke
				(width 0.1)
				(type default)
			)
			(layer "F.Fab")
		)
		(fp_line
			(start 0.2794 -0.1016)
			(end -0.2794 -0.1016)
			(stroke
				(width 0.1)
				(type default)
			)
			(layer "F.Fab")
		)
		(pad "1" smd rect
			(at 0 0 270)
			(size 0.508 0.508)
			(layers "F.Cu" "F.Mask" "F.Paste")
			(net "VR_PVCCIN_CPU1_PH4_OCSET")
		)
		(pad "2" smd rect
			(at 0 0.889 270)
			(size 0.508 0.508)
			(layers "F.Cu" "F.Mask" "F.Paste")
			(net "GND")
		)
		(zone
			(layer "F.Cu")
			(hatch none 0.5)
			(connect_pads
				(clearance 0)
			)
			(min_thickness 0.25)
			(keepout
				(tracks not_allowed)
				(vias allowed)
				(pads allowed)
				(copperpour not_allowed)
				(footprints allowed)
			)
			(placement
				(enabled no)
				(sheetname "")
			)
			(fill
				(thermal_gap 0.5)
				(thermal_bridge_width 0.5)
				(island_removal_mode 0)
			)
			(polygon
				(pts
					(xy 27.803348 -80.5688) (xy 27.803348 -80.0608) (xy 28.184348 -80.0608) (xy 28.184348 -80.5688)
				)
			)
		)
		(zone
			(layer "F.Cu")
			(hatch none 0.5)
			(connect_pads
				(clearance 0)
			)
			(min_thickness 0.25)
			(keepout
				(tracks allowed)
				(vias not_allowed)
				(pads allowed)
				(copperpour not_allowed)
				(footprints allowed)
			)
			(placement
				(enabled no)
				(sheetname "")
			)
			(fill
				(thermal_gap 0.5)
				(thermal_bridge_width 0.5)
				(island_removal_mode 0)
			)
			(polygon
				(pts
					(xy 28.184348 -80.5688) (xy 28.184348 -80.0608) (xy 27.803348 -80.0608) (xy 27.803348 -80.5688)
				)
			)
		)
	)
)
